(kicad_pcb
	(version 20260206)
	(generator "pcbnew")
	(generator_version "10.0")
	(general
		(thickness 1.6)
		(legacy_teardrops no)
	)
	(paper "A4")
	(title_block
		(title "pdpb — Lightning_PDPB_BRD.brd")
		(comment 1 "Lightning (Wiwynn / Facebook NVMe JBOF) / footprints 872-873 of 1140")
	)
	(layers
		(0 "F.Cu" signal "TOP")
		(4 "In1.Cu" signal "L2GND")
		(6 "In2.Cu" signal "L3")
		(8 "In3.Cu" signal "L4VCC")
		(10 "In4.Cu" signal "L5VCC")
		(12 "In5.Cu" signal "L6")
		(14 "In6.Cu" signal "L7GND")
		(2 "B.Cu" signal "BOTTOM")
		(9 "F.Adhes" user "F.Adhesive")
		(11 "B.Adhes" user "B.Adhesive")
		(13 "F.Paste" user "Package Geometry/Pastemask Top")
		(15 "B.Paste" user "Package Geometry/Pastemask Bottom")
		(5 "F.SilkS" user "Ref Des/Silkscreen Top")
		(7 "B.SilkS" user "Ref Des/Silkscreen Bottom")
		(1 "F.Mask" user "Board Geometry/Soldermask Top")
		(3 "B.Mask" user "Board Geometry/Soldermask Bottom")
		(17 "Dwgs.User" user "User.Drawings")
		(19 "Cmts.User" user "User.Comments")
		(21 "Eco1.User" user "User.Eco1")
		(23 "Eco2.User" user "User.Eco2")
		(25 "Edge.Cuts" user "Board Geometry/Outline")
		(27 "Margin" user)
		(31 "F.CrtYd" user "Package Geometry/Place Bound Top")
		(29 "B.CrtYd" user "Package Geometry/Place Bound Bottom")
		(35 "F.Fab" user "Ref Des/Assembly Top")
		(33 "B.Fab" user "Ref Des/Assembly Bottom")
	)
	(footprint ""
		(layer "F.Cu")
		(at 24.003 -360.045 -90)
		(property "Reference" "R9903"
			(at 0 0 270)
			(layer "F.SilkS")
			(hide yes)
			(effects
				(font
					(size 1.27 1.27)
				)
			)
		)
		(property "Value" "1K82R2F-1-GP"
			(at 0.064008 -3.993896 270)
			(unlocked yes)
			(layer "F.Fab")
			(hide yes)
			(effects
				(font
					(size 1.016 1.016)
					(thickness 0.1524)
				)
			)
		)
		(property "Device Type" "R402H16"
			(at 0.064008 -5.517896 270)
			(unlocked yes)
			(layer "F.Fab")
			(hide yes)
			(effects
				(font
					(size 1.016 1.016)
					(thickness 0.1524)
				)
			)
		)
		(duplicate_pad_numbers_are_jumpers no)
		(fp_line
			(start -0.508 -0.9398)
			(end -0.508 0.9398)
			(stroke
				(width 0.1524)
				(type default)
			)
			(layer "F.SilkS")
		)
		(fp_line
			(start 0.508 -0.9398)
			(end -0.508 -0.9398)
			(stroke
				(width 0.1524)
				(type default)
			)
			(layer "F.SilkS")
		)
		(fp_rect
			(start -0.508 0.9398)
			(end 0.508 -0.9398)
			(stroke
				(width 0)
				(type default)
			)
			(fill no)
			(layer "F.CrtYd")
		)
		(fp_rect
			(start -0.508 0.9398)
			(end 0.508 -0.9398)
			(stroke
				(width 0)
				(type default)
			)
			(fill no)
			(layer "F.Fab")
		)
		(pad "1" smd custom
			(at 0 -0.4445 270)
			(size 0.1397 0.1397)
			(layers "F.Cu" "F.Mask" "F.Paste")
			(net "P12V")
			(options
				(clearance outline)
				(anchor circle)
			)
			(primitives
				(gr_poly
					(pts
						(arc
							(start -0.1778 -0.2794)
							(mid -0.249642 -0.249642)
							(end -0.2794 -0.1778)
						)
						(arc
							(start -0.2794 0.1778)
							(mid -0.249642 0.249642)
							(end -0.1778 0.2794)
						)
						(arc
							(start 0.1778 0.2794)
							(mid 0.249642 0.249642)
							(end 0.2794 0.1778)
						)
						(arc
							(start 0.2794 -0.1778)
							(mid 0.249642 -0.249642)
							(end 0.1778 -0.2794)
						)
					)
					(width 0)
					(fill yes)
				)
			)
		)
		(pad "2" smd custom
			(at 0 0.4445 270)
			(size 0.1397 0.1397)
			(layers "F.Cu" "F.Mask" "F.Paste")
			(net "DRV_ACT_11")
			(options
				(clearance outline)
				(anchor circle)
			)
			(primitives
				(gr_poly
					(pts
						(arc
							(start -0.1778 -0.2794)
							(mid -0.249642 -0.249642)
							(end -0.2794 -0.1778)
						)
						(arc
							(start -0.2794 0.1778)
							(mid -0.249642 0.249642)
							(end -0.1778 0.2794)
						)
						(arc
							(start 0.1778 0.2794)
							(mid 0.249642 0.249642)
							(end 0.2794 0.1778)
						)
						(arc
							(start 0.2794 -0.1778)
							(mid 0.249642 -0.249642)
							(end 0.1778 -0.2794)
						)
					)
					(width 0)
					(fill yes)
				)
			)
		)
	)
	(footprint ""
		(layer "F.Cu")
		(at 99.949 -215.011)
		(property "Reference" "C8862"
			(at 0 0 0)
			(layer "F.SilkS")
			(hide yes)
			(effects
				(font
					(size 1.27 1.27)
				)
			)
		)
		(property "Value" "SCD1U16V2KX-3GP"
			(at 1.1811 -2.7051 0)
			(unlocked yes)
			(layer "F.Fab")
			(hide yes)
			(effects
				(font
					(size 1.016 1.016)
					(thickness 0.1524)
				)
			)
		)
		(property "Device Type" "C402H22"
			(at 1.1811 -4.2291 0)
			(unlocked yes)
			(layer "F.Fab")
			(hide yes)
			(effects
				(font
					(size 1.016 1.016)
					(thickness 0.1524)
				)
			)
		)
		(duplicate_pad_numbers_are_jumpers no)
		(fp_rect
			(start -0.4318 0.9525)
			(end 0.4318 -0.9525)
			(stroke
				(width 0)
				(type default)
			)
			(fill no)
			(layer "F.CrtYd")
		)
		(fp_rect
			(start -0.4318 0.9525)
			(end 0.4318 -0.9525)
			(stroke
				(width 0)
				(type default)
			)
			(fill no)
			(layer "F.Fab")
		)
		(pad "1" smd custom
			(at 0 -0.4445)
			(size 0.1524 0.1524)
			(layers "F.Cu" "F.Mask" "F.Paste")
			(net "VDD_IO_3")
			(options
				(clearance outline)
				(anchor circle)
			)
			(primitives
				(gr_poly
					(pts
						(arc
							(start 0.3048 -0.2032)
							(mid 0.275042 -0.275042)
							(end 0.2032 -0.3048)
						)
						(arc
							(start -0.2032 -0.3048)
							(mid -0.275042 -0.275042)
							(end -0.3048 -0.2032)
						)
						(arc
							(start -0.3048 0.2032)
							(mid -0.275042 0.275042)
							(end -0.2032 0.3048)
						)
						(arc
							(start 0.2032 0.3048)
							(mid 0.275042 0.275042)
							(end 0.3048 0.2032)
						)
					)
					(width 0)
					(fill yes)
				)
			)
		)
		(pad "2" smd custom
			(at 0 0.4445)
			(size 0.1524 0.1524)
			(layers "F.Cu" "F.Mask" "F.Paste")
			(net "GND")
			(options
				(clearance outline)
				(anchor circle)
			)
			(primitives
				(gr_poly
					(pts
						(arc
							(start 0.3048 -0.2032)
							(mid 0.275042 -0.275042)
							(end 0.2032 -0.3048)
						)
						(arc
							(start -0.2032 -0.3048)
							(mid -0.275042 -0.275042)
							(end -0.3048 -0.2032)
						)
						(arc
							(start -0.3048 0.2032)
							(mid -0.275042 0.275042)
							(end -0.2032 0.3048)
						)
						(arc
							(start 0.2032 0.3048)
							(mid 0.275042 0.275042)
							(end 0.3048 0.2032)
						)
					)
					(width 0)
					(fill yes)
				)
			)
		)
	)
)
